(kicad_pcb
	(version 20260206)
	(generator "pcbnew")
	(generator_version "10.0")
	(general
		(thickness 1.6)
		(legacy_teardrops no)
	)
	(paper "A4")
	(title_block
		(title "01162023_DA0F0TEBIF0_F0T_Expander_BD_F_brd_V02_OCP.brd")
		(comment 1 "Grand Teton / footprints 347-352 of 9728")
	)
	(layers
		(0 "F.Cu" signal "TOP")
		(4 "In1.Cu" signal "GND")
		(6 "In2.Cu" signal "VCC")
		(8 "In3.Cu" signal "VCC1")
		(10 "In4.Cu" signal "GND1")
		(12 "In5.Cu" signal "IN1")
		(14 "In6.Cu" signal "GND2")
		(16 "In7.Cu" signal "IN2")
		(18 "In8.Cu" signal "GND3")
		(20 "In9.Cu" signal "IN3")
		(22 "In10.Cu" signal "GND4")
		(24 "In11.Cu" signal "IN4")
		(26 "In12.Cu" signal "GND5")
		(28 "In13.Cu" signal "IN5")
		(30 "In14.Cu" signal "GND6")
		(32 "In15.Cu" signal "IN6")
		(34 "In16.Cu" signal "GND7")
		(2 "B.Cu" signal "BOTTOM")
		(9 "F.Adhes" user "F.Adhesive")
		(11 "B.Adhes" user "B.Adhesive")
		(13 "F.Paste" user "Package Geometry/Pastemask Top")
		(15 "B.Paste" user "Package Geometry/Pastemask Bottom")
		(5 "F.SilkS" user "Ref Des/Silkscreen Top")
		(7 "B.SilkS" user "Ref Des/Silkscreen Bottom")
		(1 "F.Mask" user "Board Geometry/Soldermask Top")
		(3 "B.Mask" user "Board Geometry/Soldermask Bottom")
		(17 "Dwgs.User" user "User.Drawings")
		(19 "Cmts.User" user "User.Comments")
		(21 "Eco1.User" user "User.Eco1")
		(23 "Eco2.User" user "User.Eco2")
		(25 "Edge.Cuts" user "Board Geometry/Outline")
		(27 "Margin" user)
		(31 "F.CrtYd" user "Package Geometry/Place Bound Top")
		(29 "B.CrtYd" user "Package Geometry/Place Bound Bottom")
		(35 "F.Fab" user "Ref Des/Assembly Top")
		(33 "B.Fab" user "Ref Des/Assembly Bottom")
	)
	(footprint ""
		(layer "F.Cu")
		(at 168.164256 -166.302944 90)
		(property "Reference" "R148"
			(at 0 0 90)
			(layer "F.SilkS")
			(hide yes)
			(effects
				(font
					(size 1.27 1.27)
				)
			)
		)
		(property "Value" ""
			(at 0 0 90)
			(layer "F.Fab")
			(effects
				(font
					(size 1.27 1.27)
				)
			)
		)
		(duplicate_pad_numbers_are_jumpers no)
		(fp_line
			(start 0.7874 -0.4064)
			(end 0.7874 0.4064)
			(stroke
				(width 0.1524)
				(type default)
			)
			(layer "F.SilkS")
		)
		(fp_line
			(start -0.7874 -0.4064)
			(end 0.7874 -0.4064)
			(stroke
				(width 0.1524)
				(type default)
			)
			(layer "F.SilkS")
		)
		(fp_line
			(start 0.7874 0.4064)
			(end -0.7874 0.4064)
			(stroke
				(width 0.1524)
				(type default)
			)
			(layer "F.SilkS")
		)
		(fp_line
			(start -0.7874 0.4064)
			(end -0.7874 -0.4064)
			(stroke
				(width 0.1524)
				(type default)
			)
			(layer "F.SilkS")
		)
		(fp_line
			(start -0.12065 -0.305054)
			(end -0.12065 -0.2794)
			(stroke
				(width 0.1)
				(type default)
			)
			(layer "F.Fab")
		)
		(fp_line
			(start -0.67945 -0.305054)
			(end -0.12065 -0.305054)
			(stroke
				(width 0.1)
				(type default)
			)
			(layer "F.Fab")
		)
		(fp_line
			(start 0.67945 -0.3048)
			(end 0.67945 0.3048)
			(stroke
				(width 0.1)
				(type default)
			)
			(layer "F.Fab")
		)
		(fp_line
			(start 0.12065 -0.3048)
			(end 0.67945 -0.3048)
			(stroke
				(width 0.1)
				(type default)
			)
			(layer "F.Fab")
		)
		(fp_line
			(start 0.12065 -0.2794)
			(end 0.12065 -0.3048)
			(stroke
				(width 0.1)
				(type default)
			)
			(layer "F.Fab")
		)
		(fp_line
			(start -0.12065 -0.2794)
			(end 0.12065 -0.2794)
			(stroke
				(width 0.1)
				(type default)
			)
			(layer "F.Fab")
		)
		(fp_line
			(start 0.120396 0.2794)
			(end -0.12065 0.2794)
			(stroke
				(width 0.1)
				(type default)
			)
			(layer "F.Fab")
		)
		(fp_line
			(start -0.12065 0.2794)
			(end -0.12065 0.3048)
			(stroke
				(width 0.1)
				(type default)
			)
			(layer "F.Fab")
		)
		(fp_line
			(start 0.67945 0.3048)
			(end 0.120396 0.3048)
			(stroke
				(width 0.1)
				(type default)
			)
			(layer "F.Fab")
		)
		(fp_line
			(start 0.120396 0.3048)
			(end 0.120396 0.2794)
			(stroke
				(width 0.1)
				(type default)
			)
			(layer "F.Fab")
		)
		(fp_line
			(start -0.12065 0.3048)
			(end -0.67945 0.3048)
			(stroke
				(width 0.1)
				(type default)
			)
			(layer "F.Fab")
		)
		(fp_line
			(start -0.67945 0.3048)
			(end -0.67945 -0.305054)
			(stroke
				(width 0.1)
				(type default)
			)
			(layer "F.Fab")
		)
		(pad "1" smd circle
			(at -0.40005 0 90)
			(size 0 0)
			(layers "F.Cu" "F.Mask" "F.Paste")
			(net "RST_NIC2_PERST1_R_N")
		)
		(pad "2" smd circle
			(at 0.40005 0 90)
			(size 0 0)
			(layers "F.Cu" "F.Mask" "F.Paste")
			(net "RST_HP_NIC2_BUF_N")
		)
	)
	(footprint ""
		(layer "F.Cu")
		(at 243.986812 -310.568848)
		(property "Reference" "R846"
			(at 0 0 0)
			(layer "F.SilkS")
			(hide yes)
			(effects
				(font
					(size 1.27 1.27)
				)
			)
		)
		(property "Value" ""
			(at 0 0 0)
			(layer "F.Fab")
			(effects
				(font
					(size 1.27 1.27)
				)
			)
		)
		(duplicate_pad_numbers_are_jumpers no)
		(fp_line
			(start -0.7874 -0.4064)
			(end 0.7874 -0.4064)
			(stroke
				(width 0.1524)
				(type default)
			)
			(layer "F.SilkS")
		)
		(fp_line
			(start -0.7874 0.4064)
			(end -0.7874 -0.4064)
			(stroke
				(width 0.1524)
				(type default)
			)
			(layer "F.SilkS")
		)
		(fp_line
			(start 0.7874 -0.4064)
			(end 0.7874 0.4064)
			(stroke
				(width 0.1524)
				(type default)
			)
			(layer "F.SilkS")
		)
		(fp_line
			(start 0.7874 0.4064)
			(end -0.7874 0.4064)
			(stroke
				(width 0.1524)
				(type default)
			)
			(layer "F.SilkS")
		)
		(fp_line
			(start -0.67945 -0.305054)
			(end -0.12065 -0.305054)
			(stroke
				(width 0.1)
				(type default)
			)
			(layer "F.Fab")
		)
		(fp_line
			(start -0.67945 0.3048)
			(end -0.67945 -0.305054)
			(stroke
				(width 0.1)
				(type default)
			)
			(layer "F.Fab")
		)
		(fp_line
			(start -0.12065 -0.305054)
			(end -0.12065 -0.2794)
			(stroke
				(width 0.1)
				(type default)
			)
			(layer "F.Fab")
		)
		(fp_line
			(start -0.12065 -0.2794)
			(end 0.12065 -0.2794)
			(stroke
				(width 0.1)
				(type default)
			)
			(layer "F.Fab")
		)
		(fp_line
			(start -0.12065 0.2794)
			(end -0.12065 0.3048)
			(stroke
				(width 0.1)
				(type default)
			)
			(layer "F.Fab")
		)
		(fp_line
			(start -0.12065 0.3048)
			(end -0.67945 0.3048)
			(stroke
				(width 0.1)
				(type default)
			)
			(layer "F.Fab")
		)
		(fp_line
			(start 0.120396 0.2794)
			(end -0.12065 0.2794)
			(stroke
				(width 0.1)
				(type default)
			)
			(layer "F.Fab")
		)
		(fp_line
			(start 0.120396 0.3048)
			(end 0.120396 0.2794)
			(stroke
				(width 0.1)
				(type default)
			)
			(layer "F.Fab")
		)
		(fp_line
			(start 0.12065 -0.3048)
			(end 0.67945 -0.3048)
			(stroke
				(width 0.1)
				(type default)
			)
			(layer "F.Fab")
		)
		(fp_line
			(start 0.12065 -0.2794)
			(end 0.12065 -0.3048)
			(stroke
				(width 0.1)
				(type default)
			)
			(layer "F.Fab")
		)
		(fp_line
			(start 0.67945 -0.3048)
			(end 0.67945 0.3048)
			(stroke
				(width 0.1)
				(type default)
			)
			(layer "F.Fab")
		)
		(fp_line
			(start 0.67945 0.3048)
			(end 0.120396 0.3048)
			(stroke
				(width 0.1)
				(type default)
			)
			(layer "F.Fab")
		)
		(pad "1" smd circle
			(at -0.40005 0)
			(size 0 0)
			(layers "F.Cu" "F.Mask" "F.Paste")
			(net "P1V25_PEX2_EN")
		)
		(pad "2" smd circle
			(at 0.40005 0)
			(size 0 0)
			(layers "F.Cu" "F.Mask" "F.Paste")
			(net "PWR_EN_PEX_R")
		)
	)
	(footprint ""
		(layer "F.Cu")
		(at 10.11047 -124.963428 180)
		(property "Reference" "R4474"
			(at 0 0 180)
			(layer "F.SilkS")
			(hide yes)
			(effects
				(font
					(size 1.27 1.27)
				)
			)
		)
		(property "Value" ""
			(at 0 0 180)
			(layer "F.Fab")
			(effects
				(font
					(size 1.27 1.27)
				)
			)
		)
		(duplicate_pad_numbers_are_jumpers no)
		(fp_line
			(start 0.7874 0.4064)
			(end -0.7874 0.4064)
			(stroke
				(width 0.1524)
				(type default)
			)
			(layer "F.SilkS")
		)
		(fp_line
			(start 0.7874 -0.4064)
			(end 0.7874 0.4064)
			(stroke
				(width 0.1524)
				(type default)
			)
			(layer "F.SilkS")
		)
		(fp_line
			(start -0.7874 0.4064)
			(end -0.7874 -0.4064)
			(stroke
				(width 0.1524)
				(type default)
			)
			(layer "F.SilkS")
		)
		(fp_line
			(start -0.7874 -0.4064)
			(end 0.7874 -0.4064)
			(stroke
				(width 0.1524)
				(type default)
			)
			(layer "F.SilkS")
		)
		(fp_line
			(start 0.67945 0.3048)
			(end 0.120396 0.3048)
			(stroke
				(width 0.1)
				(type default)
			)
			(layer "F.Fab")
		)
		(fp_line
			(start 0.67945 -0.3048)
			(end 0.67945 0.3048)
			(stroke
				(width 0.1)
				(type default)
			)
			(layer "F.Fab")
		)
		(fp_line
			(start 0.12065 -0.2794)
			(end 0.12065 -0.3048)
			(stroke
				(width 0.1)
				(type default)
			)
			(layer "F.Fab")
		)
		(fp_line
			(start 0.12065 -0.3048)
			(end 0.67945 -0.3048)
			(stroke
				(width 0.1)
				(type default)
			)
			(layer "F.Fab")
		)
		(fp_line
			(start 0.120396 0.3048)
			(end 0.120396 0.2794)
			(stroke
				(width 0.1)
				(type default)
			)
			(layer "F.Fab")
		)
		(fp_line
			(start 0.120396 0.2794)
			(end -0.12065 0.2794)
			(stroke
				(width 0.1)
				(type default)
			)
			(layer "F.Fab")
		)
		(fp_line
			(start -0.12065 0.3048)
			(end -0.67945 0.3048)
			(stroke
				(width 0.1)
				(type default)
			)
			(layer "F.Fab")
		)
		(fp_line
			(start -0.12065 0.2794)
			(end -0.12065 0.3048)
			(stroke
				(width 0.1)
				(type default)
			)
			(layer "F.Fab")
		)
		(fp_line
			(start -0.12065 -0.2794)
			(end 0.12065 -0.2794)
			(stroke
				(width 0.1)
				(type default)
			)
			(layer "F.Fab")
		)
		(fp_line
			(start -0.12065 -0.305054)
			(end -0.12065 -0.2794)
			(stroke
				(width 0.1)
				(type default)
			)
			(layer "F.Fab")
		)
		(fp_line
			(start -0.67945 0.3048)
			(end -0.67945 -0.305054)
			(stroke
				(width 0.1)
				(type default)
			)
			(layer "F.Fab")
		)
		(fp_line
			(start -0.67945 -0.305054)
			(end -0.12065 -0.305054)
			(stroke
				(width 0.1)
				(type default)
			)
			(layer "F.Fab")
		)
		(pad "1" smd circle
			(at -0.40005 0 180)
			(size 0 0)
			(layers "F.Cu" "F.Mask" "F.Paste")
			(net "PWRGD_P3V3_NIC0")
		)
		(pad "2" smd circle
			(at 0.40005 0 180)
			(size 0 0)
			(layers "F.Cu" "F.Mask" "F.Paste")
			(net "PWRGD_P3V3_NIC0_R")
		)
	)
	(footprint ""
		(layer "F.Cu")
		(at 257.558286 -252.356874 -90)
		(property "Reference" "R1363"
			(at 0 0 270)
			(layer "F.SilkS")
			(hide yes)
			(effects
				(font
					(size 1.27 1.27)
				)
			)
		)
		(property "Value" ""
			(at 0 0 270)
			(layer "F.Fab")
			(effects
				(font
					(size 1.27 1.27)
				)
			)
		)
		(duplicate_pad_numbers_are_jumpers no)
		(fp_line
			(start -0.7874 0.4064)
			(end -0.7874 -0.4064)
			(stroke
				(width 0.1524)
				(type default)
			)
			(layer "F.SilkS")
		)
		(fp_line
			(start 0.7874 0.4064)
			(end -0.7874 0.4064)
			(stroke
				(width 0.1524)
				(type default)
			)
			(layer "F.SilkS")
		)
		(fp_line
			(start -0.7874 -0.4064)
			(end 0.7874 -0.4064)
			(stroke
				(width 0.1524)
				(type default)
			)
			(layer "F.SilkS")
		)
		(fp_line
			(start 0.7874 -0.4064)
			(end 0.7874 0.4064)
			(stroke
				(width 0.1524)
				(type default)
			)
			(layer "F.SilkS")
		)
		(fp_line
			(start -0.67945 0.3048)
			(end -0.67945 -0.305054)
			(stroke
				(width 0.1)
				(type default)
			)
			(layer "F.Fab")
		)
		(fp_line
			(start -0.12065 0.3048)
			(end -0.67945 0.3048)
			(stroke
				(width 0.1)
				(type default)
			)
			(layer "F.Fab")
		)
		(fp_line
			(start 0.120396 0.3048)
			(end 0.120396 0.2794)
			(stroke
				(width 0.1)
				(type default)
			)
			(layer "F.Fab")
		)
		(fp_line
			(start 0.67945 0.3048)
			(end 0.120396 0.3048)
			(stroke
				(width 0.1)
				(type default)
			)
			(layer "F.Fab")
		)
		(fp_line
			(start -0.12065 0.2794)
			(end -0.12065 0.3048)
			(stroke
				(width 0.1)
				(type default)
			)
			(layer "F.Fab")
		)
		(fp_line
			(start 0.120396 0.2794)
			(end -0.12065 0.2794)
			(stroke
				(width 0.1)
				(type default)
			)
			(layer "F.Fab")
		)
		(fp_line
			(start -0.12065 -0.2794)
			(end 0.12065 -0.2794)
			(stroke
				(width 0.1)
				(type default)
			)
			(layer "F.Fab")
		)
		(fp_line
			(start 0.12065 -0.2794)
			(end 0.12065 -0.3048)
			(stroke
				(width 0.1)
				(type default)
			)
			(layer "F.Fab")
		)
		(fp_line
			(start 0.12065 -0.3048)
			(end 0.67945 -0.3048)
			(stroke
				(width 0.1)
				(type default)
			)
			(layer "F.Fab")
		)
		(fp_line
			(start 0.67945 -0.3048)
			(end 0.67945 0.3048)
			(stroke
				(width 0.1)
				(type default)
			)
			(layer "F.Fab")
		)
		(fp_line
			(start -0.67945 -0.305054)
			(end -0.12065 -0.305054)
			(stroke
				(width 0.1)
				(type default)
			)
			(layer "F.Fab")
		)
		(fp_line
			(start -0.12065 -0.305054)
			(end -0.12065 -0.2794)
			(stroke
				(width 0.1)
				(type default)
			)
			(layer "F.Fab")
		)
		(pad "1" smd circle
			(at -0.40005 0 270)
			(size 0 0)
			(layers "F.Cu" "F.Mask" "F.Paste")
			(net "GND")
		)
		(pad "2" smd circle
			(at 0.40005 0 270)
			(size 0 0)
			(layers "F.Cu" "F.Mask" "F.Paste")
			(net "PEX2_MODE_SEL7")
		)
	)
	(footprint ""
		(layer "F.Cu")
		(at 378.826776 -53.697124 -90)
		(property "Reference" "PC556"
			(at 0 0 270)
			(layer "F.SilkS")
			(hide yes)
			(effects
				(font
					(size 1.27 1.27)
				)
			)
		)
		(property "Value" ""
			(at 0 0 270)
			(layer "F.Fab")
			(effects
				(font
					(size 1.27 1.27)
				)
			)
		)
		(duplicate_pad_numbers_are_jumpers no)
		(fp_line
			(start -0.7874 0.4064)
			(end -0.7874 -0.4064)
			(stroke
				(width 0.1524)
				(type default)
			)
			(layer "F.SilkS")
		)
		(fp_line
			(start 0.7874 0.4064)
			(end -0.7874 0.4064)
			(stroke
				(width 0.1524)
				(type default)
			)
			(layer "F.SilkS")
		)
		(fp_line
			(start -0.7874 -0.4064)
			(end 0.7874 -0.4064)
			(stroke
				(width 0.1524)
				(type default)
			)
			(layer "F.SilkS")
		)
		(fp_line
			(start 0.7874 -0.4064)
			(end 0.7874 0.4064)
			(stroke
				(width 0.1524)
				(type default)
			)
			(layer "F.SilkS")
		)
		(fp_line
			(start -0.67945 0.3048)
			(end -0.67945 -0.305054)
			(stroke
				(width 0.1)
				(type default)
			)
			(layer "F.Fab")
		)
		(fp_line
			(start -0.12065 0.3048)
			(end -0.67945 0.3048)
			(stroke
				(width 0.1)
				(type default)
			)
			(layer "F.Fab")
		)
		(fp_line
			(start 0.120396 0.3048)
			(end 0.120396 0.2794)
			(stroke
				(width 0.1)
				(type default)
			)
			(layer "F.Fab")
		)
		(fp_line
			(start 0.67945 0.3048)
			(end 0.120396 0.3048)
			(stroke
				(width 0.1)
				(type default)
			)
			(layer "F.Fab")
		)
		(fp_line
			(start -0.12065 0.2794)
			(end -0.12065 0.3048)
			(stroke
				(width 0.1)
				(type default)
			)
			(layer "F.Fab")
		)
		(fp_line
			(start 0.120396 0.2794)
			(end -0.12065 0.2794)
			(stroke
				(width 0.1)
				(type default)
			)
			(layer "F.Fab")
		)
		(fp_line
			(start -0.12065 -0.2794)
			(end 0.12065 -0.2794)
			(stroke
				(width 0.1)
				(type default)
			)
			(layer "F.Fab")
		)
		(fp_line
			(start 0.12065 -0.2794)
			(end 0.12065 -0.3048)
			(stroke
				(width 0.1)
				(type default)
			)
			(layer "F.Fab")
		)
		(fp_line
			(start 0.12065 -0.3048)
			(end 0.67945 -0.3048)
			(stroke
				(width 0.1)
				(type default)
			)
			(layer "F.Fab")
		)
		(fp_line
			(start 0.67945 -0.3048)
			(end 0.67945 0.3048)
			(stroke
				(width 0.1)
				(type default)
			)
			(layer "F.Fab")
		)
		(fp_line
			(start -0.67945 -0.305054)
			(end -0.12065 -0.305054)
			(stroke
				(width 0.1)
				(type default)
			)
			(layer "F.Fab")
		)
		(fp_line
			(start -0.12065 -0.305054)
			(end -0.12065 -0.2794)
			(stroke
				(width 0.1)
				(type default)
			)
			(layer "F.Fab")
		)
		(pad "1" smd circle
			(at -0.40005 0 270)
			(size 0 0)
			(layers "F.Cu" "F.Mask" "F.Paste")
			(net "P3V3_AUX")
		)
		(pad "2" smd circle
			(at 0.40005 0 270)
			(size 0 0)
			(layers "F.Cu" "F.Mask" "F.Paste")
			(net "GND")
		)
	)
	(footprint ""
		(layer "F.Cu")
		(at 334.518 -201.168 -90)
		(property "Reference" "R4119"
			(at 0 0 270)
			(layer "F.SilkS")
			(hide yes)
			(effects
				(font
					(size 1.27 1.27)
				)
			)
		)
		(property "Value" ""
			(at 0 0 270)
			(layer "F.Fab")
			(effects
				(font
					(size 1.27 1.27)
				)
			)
		)
		(duplicate_pad_numbers_are_jumpers no)
		(fp_line
			(start -0.7874 0.4064)
			(end -0.7874 -0.4064)
			(stroke
				(width 0.1524)
				(type default)
			)
			(layer "F.SilkS")
		)
		(fp_line
			(start 0.7874 0.4064)
			(end -0.7874 0.4064)
			(stroke
				(width 0.1524)
				(type default)
			)
			(layer "F.SilkS")
		)
		(fp_line
			(start -0.7874 -0.4064)
			(end 0.7874 -0.4064)
			(stroke
				(width 0.1524)
				(type default)
			)
			(layer "F.SilkS")
		)
		(fp_line
			(start 0.7874 -0.4064)
			(end 0.7874 0.4064)
			(stroke
				(width 0.1524)
				(type default)
			)
			(layer "F.SilkS")
		)
		(fp_line
			(start -0.67945 0.3048)
			(end -0.67945 -0.305054)
			(stroke
				(width 0.1)
				(type default)
			)
			(layer "F.Fab")
		)
		(fp_line
			(start -0.12065 0.3048)
			(end -0.67945 0.3048)
			(stroke
				(width 0.1)
				(type default)
			)
			(layer "F.Fab")
		)
		(fp_line
			(start 0.120396 0.3048)
			(end 0.120396 0.2794)
			(stroke
				(width 0.1)
				(type default)
			)
			(layer "F.Fab")
		)
		(fp_line
			(start 0.67945 0.3048)
			(end 0.120396 0.3048)
			(stroke
				(width 0.1)
				(type default)
			)
			(layer "F.Fab")
		)
		(fp_line
			(start -0.12065 0.2794)
			(end -0.12065 0.3048)
			(stroke
				(width 0.1)
				(type default)
			)
			(layer "F.Fab")
		)
		(fp_line
			(start 0.120396 0.2794)
			(end -0.12065 0.2794)
			(stroke
				(width 0.1)
				(type default)
			)
			(layer "F.Fab")
		)
		(fp_line
			(start -0.12065 -0.2794)
			(end 0.12065 -0.2794)
			(stroke
				(width 0.1)
				(type default)
			)
			(layer "F.Fab")
		)
		(fp_line
			(start 0.12065 -0.2794)
			(end 0.12065 -0.3048)
			(stroke
				(width 0.1)
				(type default)
			)
			(layer "F.Fab")
		)
		(fp_line
			(start 0.12065 -0.3048)
			(end 0.67945 -0.3048)
			(stroke
				(width 0.1)
				(type default)
			)
			(layer "F.Fab")
		)
		(fp_line
			(start 0.67945 -0.3048)
			(end 0.67945 0.3048)
			(stroke
				(width 0.1)
				(type default)
			)
			(layer "F.Fab")
		)
		(fp_line
			(start -0.67945 -0.305054)
			(end -0.12065 -0.305054)
			(stroke
				(width 0.1)
				(type default)
			)
			(layer "F.Fab")
		)
		(fp_line
			(start -0.12065 -0.305054)
			(end -0.12065 -0.2794)
			(stroke
				(width 0.1)
				(type default)
			)
			(layer "F.Fab")
		)
		(pad "1" smd circle
			(at -0.40005 0 270)
			(size 0 0)
			(layers "F.Cu" "F.Mask" "F.Paste")
			(net "SSD9_PWR_EN")
		)
		(pad "2" smd circle
			(at 0.40005 0 270)
			(size 0 0)
			(layers "F.Cu" "F.Mask" "F.Paste")
			(net "SSD9_PWR_EN_R")
		)
	)
)
